(kicad_pcb
	(version 20221018)
	(generator pcbnew)
	(general
    (thickness 1.62)
  )
	(paper "A4")
	(title_block
    (title "ECP5 - Datacenter Secure Control Module (DC-SCM)")
    (date "2024-07-01")
    (rev "1.2.1")
		(comment 9 "footprints 426-433 of 506")
	)
	(layers
    (0 "F.Cu" signal)
    (1 "In1.Cu" power)
    (2 "In2.Cu" signal)
    (3 "In3.Cu" power)
    (4 "In4.Cu" power)
    (5 "In5.Cu" signal)
    (6 "In6.Cu" power)
    (31 "B.Cu" signal)
    (32 "B.Adhes" user "B.Adhesive")
    (33 "F.Adhes" user "F.Adhesive")
    (34 "B.Paste" user)
    (35 "F.Paste" user)
    (36 "B.SilkS" user "B.Silkscreen")
    (37 "F.SilkS" user "F.Silkscreen")
    (38 "B.Mask" user)
    (39 "F.Mask" user)
    (40 "Dwgs.User" user "User.Drawings")
    (41 "Cmts.User" user "User.Comments")
    (42 "Eco1.User" user "User.Eco1")
    (43 "Eco2.User" user "User.Eco2")
    (44 "Edge.Cuts" user)
    (45 "Margin" user)
    (46 "B.CrtYd" user "B.Courtyard")
    (47 "F.CrtYd" user "F.Courtyard")
    (48 "B.Fab" user)
    (49 "F.Fab" user)
  )
	(footprint "antmicro-footprints:R_Array_8x0602_Panasonic_EXB2HV" (layer "B.Cu")
    (at 84.77 124.595 -90)
    (descr "Chip Resistor Network, ROHM MNR18")
    (tags "resistor array")
    (property "Author" "Antmicro")
    (property "License" "Apache-2.0")
    (property "MPN" "EXB2HV510JV")
    (property "Manufacturer" "Panasonic")
    (property "Sheetfile" "ddr3.kicad_sch")
    (property "Sheetname" "DDR3")
    (property "Val" "8x51R_0602")
    (property "ki_description" "Fixed Network Resistor, 51 ohm, Isolated, 8 Resistors, 1506 [3816 Metric], Convex, ± 5%")
    (property "ki_keywords" "SMT, RESISTOR, PASSIVE, ARRAY")
    (attr smd)
    (fp_text reference "R136" (at -0.84 -3.59 180) (layer "B.SilkS")
        (effects (font (size 0.7 0.7) (thickness 0.127)) (justify mirror))
    )
    (fp_text value "8x51R_0602_array" (at 0 -3 90) (layer "B.Fab")
        (effects (font (size 1 1) (thickness 0.15)) (justify mirror))
    )
    (fp_text user "${REFERENCE}" (at 0 0 180) (layer "B.Fab")
        (effects (font (size 1 1) (thickness 0.15)) (justify mirror))
    )
    (fp_text user "License: Apache-2.0" (at -1.55 -7.45 90) (layer "B.Fab") hide
        (effects (font (size 0.7 0.7) (thickness 0.15)) (justify left bottom mirror))
    )
    (fp_text user "Author: Antmicro" (at -1.55 -5.05 90) (layer "B.Fab") hide
        (effects (font (size 0.7 0.7) (thickness 0.15)) (justify left bottom mirror))
    )
    (fp_line (start 0.5 -2.12) (end -0.5 -2.12)
      (stroke (width 0.15) (type solid)) (layer "B.SilkS"))
    (fp_line (start 0.5 2.12) (end -0.5 2.12)
      (stroke (width 0.15) (type solid)) (layer "B.SilkS"))
    (fp_circle (center -1.05 2.05) (end -1 2.05)
      (stroke (width 0.15) (type solid)) (fill solid) (layer "B.SilkS"))
    (fp_rect (start -1.55 2.2) (end 1.55 -2.2)
      (stroke (width 0.05) (type solid)) (fill none) (layer "B.CrtYd"))
    (fp_line (start -0.8 -2) (end 0.8 -2)
      (stroke (width 0.15) (type solid)) (layer "B.Fab"))
    (fp_line (start -0.8 2) (end -0.8 -2)
      (stroke (width 0.15) (type solid)) (layer "B.Fab"))
    (fp_line (start 0.8 -2) (end 0.8 2)
      (stroke (width 0.15) (type solid)) (layer "B.Fab"))
    (fp_line (start 0.8 2) (end -0.8 2)
      (stroke (width 0.15) (type solid)) (layer "B.Fab"))
    (pad "1" smd rect (at -0.9 1.75 270) (size 0.8 0.3) (layers "B.Cu" "B.Paste" "B.Mask")
      (net 246 "DDR3_A0") (pinfunction "1") (pintype "passive"))
    (pad "2" smd rect (at -0.9 1.25 270) (size 0.8 0.3) (layers "B.Cu" "B.Paste" "B.Mask")
      (net 252 "DDR3_BA2") (pinfunction "2") (pintype "passive"))
    (pad "3" smd rect (at -0.9 0.75 270) (size 0.8 0.3) (layers "B.Cu" "B.Paste" "B.Mask")
      (net 251 "DDR3_WE") (pinfunction "3") (pintype "passive"))
    (pad "4" smd rect (at -0.9 0.25 270) (size 0.8 0.3) (layers "B.Cu" "B.Paste" "B.Mask")
      (net 258 "DDR3_RAS") (pinfunction "4") (pintype "passive"))
    (pad "5" smd rect (at -0.9 -0.25 270) (size 0.8 0.3) (layers "B.Cu" "B.Paste" "B.Mask")
      (net 254 "DDR3_CAS") (pinfunction "5") (pintype "passive"))
    (pad "6" smd rect (at -0.9 -0.75 270) (size 0.8 0.3) (layers "B.Cu" "B.Paste" "B.Mask")
      (net 257 "DDR3_CS") (pinfunction "6") (pintype "passive"))
    (pad "7" smd rect (at -0.9 -1.25 270) (size 0.8 0.3) (layers "B.Cu" "B.Paste" "B.Mask")
      (net 256 "DDR3_BA0") (pinfunction "7") (pintype "passive"))
    (pad "8" smd rect (at -0.9 -1.75 270) (size 0.8 0.3) (layers "B.Cu" "B.Paste" "B.Mask")
      (net 259 "DDR3_ODT") (pinfunction "8") (pintype "passive"))
    (pad "9" smd rect (at 0.9 -1.75 270) (size 0.8 0.3) (layers "B.Cu" "B.Paste" "B.Mask")
      (net 166 "/DDR3/DDR3_VTT") (pinfunction "9") (pintype "passive"))
    (pad "10" smd rect (at 0.9 -1.25 270) (size 0.8 0.3) (layers "B.Cu" "B.Paste" "B.Mask")
      (net 166 "/DDR3/DDR3_VTT") (pinfunction "10") (pintype "passive"))
    (pad "11" smd rect (at 0.9 -0.75 270) (size 0.8 0.3) (layers "B.Cu" "B.Paste" "B.Mask")
      (net 166 "/DDR3/DDR3_VTT") (pinfunction "11") (pintype "passive"))
    (pad "12" smd rect (at 0.9 -0.25 270) (size 0.8 0.3) (layers "B.Cu" "B.Paste" "B.Mask")
      (net 166 "/DDR3/DDR3_VTT") (pinfunction "12") (pintype "passive"))
    (pad "13" smd rect (at 0.9 0.25 270) (size 0.8 0.3) (layers "B.Cu" "B.Paste" "B.Mask")
      (net 166 "/DDR3/DDR3_VTT") (pinfunction "13") (pintype "passive"))
    (pad "14" smd rect (at 0.9 0.75 270) (size 0.8 0.3) (layers "B.Cu" "B.Paste" "B.Mask")
      (net 166 "/DDR3/DDR3_VTT") (pinfunction "14") (pintype "passive"))
    (pad "15" smd rect (at 0.9 1.25 270) (size 0.8 0.3) (layers "B.Cu" "B.Paste" "B.Mask")
      (net 166 "/DDR3/DDR3_VTT") (pinfunction "15") (pintype "passive"))
    (pad "16" smd rect (at 0.9 1.75 270) (size 0.8 0.3) (layers "B.Cu" "B.Paste" "B.Mask")
      (net 166 "/DDR3/DDR3_VTT") (pinfunction "16") (pintype "passive"))
  )
	(footprint "antmicro-footprints:R_0402_1005Metric" (layer "B.Cu")
    (at 87.45 135.6 90)
    (descr "Resistor SMD 0402")
    (tags "resistor SMD 0402")
    (property "Author" "Antmicro")
    (property "Current" "1A")
    (property "DNP" "DNP")
    (property "License" "Apache-2.0")
    (property "MPN" "ERJ2GE0R00X")
    (property "Manufacturer" "Panasonic")
    (property "Public" "False")
    (property "Sheetfile" "fpga-banks.kicad_sch")
    (property "Sheetname" "FPGA banks")
    (property "Tolerance" "")
    (property "Val" "0R")
    (property "dnp" "")
    (property "exclude_from_bom" "")
    (property "ki_description" "SMD Chip Resistor, Jumper, 0 ohm, 100 mW, 0402 [1005 Metric], Thick Film, General Purpose")
    (property "ki_keywords" "0402, SMT, RESISTOR, PASSIVE")
    (attr smd exclude_from_pos_files exclude_from_bom)
    (fp_text reference "R133" (at -2.35 0.02 90) (layer "B.SilkS")
        (effects (font (size 0.7 0.7) (thickness 0.127)) (justify mirror))
    )
    (fp_text value "R_0R_0402" (at 0 -1.17 90) (layer "B.Fab")
        (effects (font (size 1 1) (thickness 0.15)) (justify mirror))
    )
    (fp_text user "License: Apache-2.0" (at -0.95 -5.169 270) (layer "B.Fab") hide
        (effects (font (size 0.7 0.7) (thickness 0.15)) (justify left bottom mirror))
    )
    (fp_text user "${REFERENCE}" (at 0 0 90) (layer "B.Fab")
        (effects (font (size 0.25 0.25) (thickness 0.04)) (justify mirror))
    )
    (fp_text user "Author: Antmicro" (at -0.95 -4.169 270) (layer "B.Fab") hide
        (effects (font (size 0.7 0.7) (thickness 0.15)) (justify left bottom mirror))
    )
    (fp_rect (start -0.925 0.47) (end 0.925 -0.47)
      (stroke (width 0.05) (type default)) (fill none) (layer "B.CrtYd"))
    (fp_rect (start -0.5 0.25) (end 0.5 -0.25)
      (stroke (width 0.15) (type solid)) (fill none) (layer "B.Fab"))
    (pad "1" smd roundrect (at -0.48 0 90) (size 0.59 0.64) (layers "B.Cu" "B.Paste" "B.Mask") (roundrect_rratio 0.25)
      (net 53 "SPI0_CS_N") (pintype "passive"))
    (pad "2" smd roundrect (at 0.48 0 90) (size 0.59 0.64) (layers "B.Cu" "B.Paste" "B.Mask") (roundrect_rratio 0.25)
      (net 428 "Net-(U21I-PB4B)") (pintype "passive"))
  )
	(footprint "antmicro-footprints:R_0402_1005Metric" (layer "B.Cu")
    (at 89.55 135.6 90)
    (descr "Resistor SMD 0402")
    (tags "resistor SMD 0402")
    (property "Author" "Antmicro")
    (property "Current" "1A")
    (property "DNP" "DNP")
    (property "License" "Apache-2.0")
    (property "MPN" "ERJ2GE0R00X")
    (property "Manufacturer" "Panasonic")
    (property "Public" "False")
    (property "Sheetfile" "fpga-banks.kicad_sch")
    (property "Sheetname" "FPGA banks")
    (property "Tolerance" "")
    (property "Val" "0R")
    (property "dnp" "")
    (property "exclude_from_bom" "")
    (property "ki_description" "SMD Chip Resistor, Jumper, 0 ohm, 100 mW, 0402 [1005 Metric], Thick Film, General Purpose")
    (property "ki_keywords" "0402, SMT, RESISTOR, PASSIVE")
    (attr smd exclude_from_pos_files exclude_from_bom)
    (fp_text reference "R134" (at -2.35 0.02 90) (layer "B.SilkS")
        (effects (font (size 0.7 0.7) (thickness 0.127)) (justify mirror))
    )
    (fp_text value "R_0R_0402" (at 0 -1.17 90) (layer "B.Fab")
        (effects (font (size 1 1) (thickness 0.15)) (justify mirror))
    )
    (fp_text user "${REFERENCE}" (at 0 0 90) (layer "B.Fab")
        (effects (font (size 0.25 0.25) (thickness 0.04)) (justify mirror))
    )
    (fp_text user "Author: Antmicro" (at -0.95 -4.169 270) (layer "B.Fab") hide
        (effects (font (size 0.7 0.7) (thickness 0.15)) (justify left bottom mirror))
    )
    (fp_text user "License: Apache-2.0" (at -0.95 -5.169 270) (layer "B.Fab") hide
        (effects (font (size 0.7 0.7) (thickness 0.15)) (justify left bottom mirror))
    )
    (fp_rect (start -0.925 0.47) (end 0.925 -0.47)
      (stroke (width 0.05) (type default)) (fill none) (layer "B.CrtYd"))
    (fp_rect (start -0.5 0.25) (end 0.5 -0.25)
      (stroke (width 0.15) (type solid)) (fill none) (layer "B.Fab"))
    (pad "1" smd roundrect (at -0.48 0 90) (size 0.59 0.64) (layers "B.Cu" "B.Paste" "B.Mask") (roundrect_rratio 0.25)
      (net 55 "SPI0_MOSI") (pintype "passive"))
    (pad "2" smd roundrect (at 0.48 0 90) (size 0.59 0.64) (layers "B.Cu" "B.Paste" "B.Mask") (roundrect_rratio 0.25)
      (net 429 "Net-(U21I-PB6B)") (pintype "passive"))
  )
	(footprint "antmicro-footprints:R_0402_1005Metric" (layer "B.Cu")
    (at 88.5 135.6 90)
    (descr "Resistor SMD 0402")
    (tags "resistor SMD 0402")
    (property "Author" "Antmicro")
    (property "Current" "1A")
    (property "DNP" "DNP")
    (property "License" "Apache-2.0")
    (property "MPN" "ERJ2GE0R00X")
    (property "Manufacturer" "Panasonic")
    (property "Public" "False")
    (property "Sheetfile" "fpga-banks.kicad_sch")
    (property "Sheetname" "FPGA banks")
    (property "Tolerance" "")
    (property "Val" "0R")
    (property "dnp" "")
    (property "exclude_from_bom" "")
    (property "ki_description" "SMD Chip Resistor, Jumper, 0 ohm, 100 mW, 0402 [1005 Metric], Thick Film, General Purpose")
    (property "ki_keywords" "0402, SMT, RESISTOR, PASSIVE")
    (attr smd exclude_from_pos_files exclude_from_bom)
    (fp_text reference "R135" (at -2.35 0.02 90) (layer "B.SilkS")
        (effects (font (size 0.7 0.7) (thickness 0.127)) (justify mirror))
    )
    (fp_text value "R_0R_0402" (at 0 -1.17 90) (layer "B.Fab")
        (effects (font (size 1 1) (thickness 0.15)) (justify mirror))
    )
    (fp_text user "Author: Antmicro" (at -0.95 -4.169 270) (layer "B.Fab") hide
        (effects (font (size 0.7 0.7) (thickness 0.15)) (justify left bottom mirror))
    )
    (fp_text user "${REFERENCE}" (at 0 0 90) (layer "B.Fab")
        (effects (font (size 0.25 0.25) (thickness 0.04)) (justify mirror))
    )
    (fp_text user "License: Apache-2.0" (at -0.95 -5.169 270) (layer "B.Fab") hide
        (effects (font (size 0.7 0.7) (thickness 0.15)) (justify left bottom mirror))
    )
    (fp_rect (start -0.925 0.47) (end 0.925 -0.47)
      (stroke (width 0.05) (type default)) (fill none) (layer "B.CrtYd"))
    (fp_rect (start -0.5 0.25) (end 0.5 -0.25)
      (stroke (width 0.15) (type solid)) (fill none) (layer "B.Fab"))
    (pad "1" smd roundrect (at -0.48 0 90) (size 0.59 0.64) (layers "B.Cu" "B.Paste" "B.Mask") (roundrect_rratio 0.25)
      (net 56 "SPI0_MISO") (pintype "passive"))
    (pad "2" smd roundrect (at 0.48 0 90) (size 0.59 0.64) (layers "B.Cu" "B.Paste" "B.Mask") (roundrect_rratio 0.25)
      (net 431 "Net-(U21I-PB6A)") (pintype "passive"))
  )
	(footprint "antmicro-footprints:R_0402_1005Metric" (layer "B.Cu")
    (at 90.649 143.0942)
    (descr "Resistor SMD 0402")
    (tags "resistor SMD 0402")
    (property "Author" "Antmicro")
    (property "License" "Apache-2.0")
    (property "MPN" "CR0402-FX-3573GLF")
    (property "Manufacturer" "Bourns")
    (property "Public" "False")
    (property "Sheetfile" "interfaces.kicad_sch")
    (property "Sheetname" "Interfaces")
    (property "Tolerance" "1%")
    (property "Val" "357k")
    (property "ki_description" "SMD Chip Resistor")
    (property "ki_keywords" "0402, SMT, RESISTOR, PASSIVE")
    (attr smd)
    (fp_text reference "R49" (at -2.2 -0.03) (layer "B.SilkS")
        (effects (font (size 0.7 0.7) (thickness 0.127)) (justify mirror))
    )
    (fp_text value "R_357k_0402" (at 0 -1.17) (layer "B.Fab")
        (effects (font (size 1 1) (thickness 0.15)) (justify mirror))
    )
    (fp_text user "Author: Antmicro" (at -0.95 -4.169 180) (layer "B.Fab") hide
        (effects (font (size 0.7 0.7) (thickness 0.15)) (justify left bottom mirror))
    )
    (fp_text user "${REFERENCE}" (at 0 0) (layer "B.Fab")
        (effects (font (size 0.25 0.25) (thickness 0.04)) (justify mirror))
    )
    (fp_text user "License: Apache-2.0" (at -0.95 -5.169 180) (layer "B.Fab") hide
        (effects (font (size 0.7 0.7) (thickness 0.15)) (justify left bottom mirror))
    )
    (fp_rect (start -0.925 0.47) (end 0.925 -0.47)
      (stroke (width 0.05) (type default)) (fill none) (layer "B.CrtYd"))
    (fp_rect (start -0.5 0.25) (end 0.5 -0.25)
      (stroke (width 0.15) (type solid)) (fill none) (layer "B.Fab"))
    (pad "1" smd roundrect (at -0.48 0) (size 0.59 0.64) (layers "B.Cu" "B.Paste" "B.Mask") (roundrect_rratio 0.25)
      (net 2 "VCC3V3") (pintype "passive"))
    (pad "2" smd roundrect (at 0.48 0) (size 0.59 0.64) (layers "B.Cu" "B.Paste" "B.Mask") (roundrect_rratio 0.25)
      (net 167 "I3C[0]_SDA_3V3") (pintype "passive"))
  )
	(footprint "antmicro-footprints:R_0402_1005Metric" (layer "B.Cu")
    (at 90.649 142.0742)
    (descr "Resistor SMD 0402")
    (tags "resistor SMD 0402")
    (property "Author" "Antmicro")
    (property "License" "Apache-2.0")
    (property "MPN" "CR0402-FX-3573GLF")
    (property "Manufacturer" "Bourns")
    (property "Public" "False")
    (property "Sheetfile" "interfaces.kicad_sch")
    (property "Sheetname" "Interfaces")
    (property "Tolerance" "1%")
    (property "Val" "357k")
    (property "ki_description" "SMD Chip Resistor")
    (property "ki_keywords" "0402, SMT, RESISTOR, PASSIVE")
    (attr smd)
    (fp_text reference "R50" (at -2.2 -0.03) (layer "B.SilkS")
        (effects (font (size 0.7 0.7) (thickness 0.127)) (justify mirror))
    )
    (fp_text value "R_357k_0402" (at 0 -1.17) (layer "B.Fab")
        (effects (font (size 1 1) (thickness 0.15)) (justify mirror))
    )
    (fp_text user "License: Apache-2.0" (at -0.95 -5.169 180) (layer "B.Fab") hide
        (effects (font (size 0.7 0.7) (thickness 0.15)) (justify left bottom mirror))
    )
    (fp_text user "${REFERENCE}" (at 0 0) (layer "B.Fab")
        (effects (font (size 0.25 0.25) (thickness 0.04)) (justify mirror))
    )
    (fp_text user "Author: Antmicro" (at -0.95 -4.169 180) (layer "B.Fab") hide
        (effects (font (size 0.7 0.7) (thickness 0.15)) (justify left bottom mirror))
    )
    (fp_rect (start -0.925 0.47) (end 0.925 -0.47)
      (stroke (width 0.05) (type default)) (fill none) (layer "B.CrtYd"))
    (fp_rect (start -0.5 0.25) (end 0.5 -0.25)
      (stroke (width 0.15) (type solid)) (fill none) (layer "B.Fab"))
    (pad "1" smd roundrect (at -0.48 0) (size 0.59 0.64) (layers "B.Cu" "B.Paste" "B.Mask") (roundrect_rratio 0.25)
      (net 2 "VCC3V3") (pintype "passive"))
    (pad "2" smd roundrect (at 0.48 0) (size 0.59 0.64) (layers "B.Cu" "B.Paste" "B.Mask") (roundrect_rratio 0.25)
      (net 168 "I3C[0]_SCL_3V3") (pintype "passive"))
  )
	(footprint "antmicro-footprints:R_0402_1005Metric" (layer "B.Cu")
    (at 90.649 145.0742)
    (descr "Resistor SMD 0402")
    (tags "resistor SMD 0402")
    (property "Author" "Antmicro")
    (property "License" "Apache-2.0")
    (property "MPN" "CR0402-FX-3573GLF")
    (property "Manufacturer" "Bourns")
    (property "Public" "False")
    (property "Sheetfile" "interfaces.kicad_sch")
    (property "Sheetname" "Interfaces")
    (property "Tolerance" "1%")
    (property "Val" "357k")
    (property "ki_description" "SMD Chip Resistor")
    (property "ki_keywords" "0402, SMT, RESISTOR, PASSIVE")
    (attr smd)
    (fp_text reference "R51" (at -2.2 -0.03) (layer "B.SilkS")
        (effects (font (size 0.7 0.7) (thickness 0.127)) (justify mirror))
    )
    (fp_text value "R_357k_0402" (at 0 -1.17) (layer "B.Fab")
        (effects (font (size 1 1) (thickness 0.15)) (justify mirror))
    )
    (fp_text user "${REFERENCE}" (at 0 0) (layer "B.Fab")
        (effects (font (size 0.25 0.25) (thickness 0.04)) (justify mirror))
    )
    (fp_text user "Author: Antmicro" (at -0.95 -4.169 180) (layer "B.Fab") hide
        (effects (font (size 0.7 0.7) (thickness 0.15)) (justify left bottom mirror))
    )
    (fp_text user "License: Apache-2.0" (at -0.95 -5.169 180) (layer "B.Fab") hide
        (effects (font (size 0.7 0.7) (thickness 0.15)) (justify left bottom mirror))
    )
    (fp_rect (start -0.925 0.47) (end 0.925 -0.47)
      (stroke (width 0.05) (type default)) (fill none) (layer "B.CrtYd"))
    (fp_rect (start -0.5 0.25) (end 0.5 -0.25)
      (stroke (width 0.15) (type solid)) (fill none) (layer "B.Fab"))
    (pad "1" smd roundrect (at -0.48 0) (size 0.59 0.64) (layers "B.Cu" "B.Paste" "B.Mask") (roundrect_rratio 0.25)
      (net 2 "VCC3V3") (pintype "passive"))
    (pad "2" smd roundrect (at 0.48 0) (size 0.59 0.64) (layers "B.Cu" "B.Paste" "B.Mask") (roundrect_rratio 0.25)
      (net 169 "I3C[1]_SDA_3V3") (pintype "passive"))
  )
	(footprint "antmicro-footprints:R_0402_1005Metric" (layer "B.Cu")
    (at 90.649 144.0742)
    (descr "Resistor SMD 0402")
    (tags "resistor SMD 0402")
    (property "Author" "Antmicro")
    (property "License" "Apache-2.0")
    (property "MPN" "CR0402-FX-3573GLF")
    (property "Manufacturer" "Bourns")
    (property "Public" "False")
    (property "Sheetfile" "interfaces.kicad_sch")
    (property "Sheetname" "Interfaces")
    (property "Tolerance" "1%")
    (property "Val" "357k")
    (property "ki_description" "SMD Chip Resistor")
    (property "ki_keywords" "0402, SMT, RESISTOR, PASSIVE")
    (attr smd)
    (fp_text reference "R52" (at -2.2 -0.03) (layer "B.SilkS")
        (effects (font (size 0.7 0.7) (thickness 0.127)) (justify mirror))
    )
    (fp_text value "R_357k_0402" (at 0 -1.17) (layer "B.Fab")
        (effects (font (size 1 1) (thickness 0.15)) (justify mirror))
    )
    (fp_text user "Author: Antmicro" (at -0.95 -4.169 180) (layer "B.Fab") hide
        (effects (font (size 0.7 0.7) (thickness 0.15)) (justify left bottom mirror))
    )
    (fp_text user "License: Apache-2.0" (at -0.95 -5.169 180) (layer "B.Fab") hide
        (effects (font (size 0.7 0.7) (thickness 0.15)) (justify left bottom mirror))
    )
    (fp_text user "${REFERENCE}" (at 0 0) (layer "B.Fab")
        (effects (font (size 0.25 0.25) (thickness 0.04)) (justify mirror))
    )
    (fp_rect (start -0.925 0.47) (end 0.925 -0.47)
      (stroke (width 0.05) (type default)) (fill none) (layer "B.CrtYd"))
    (fp_rect (start -0.5 0.25) (end 0.5 -0.25)
      (stroke (width 0.15) (type solid)) (fill none) (layer "B.Fab"))
    (pad "1" smd roundrect (at -0.48 0) (size 0.59 0.64) (layers "B.Cu" "B.Paste" "B.Mask") (roundrect_rratio 0.25)
      (net 2 "VCC3V3") (pintype "passive"))
    (pad "2" smd roundrect (at 0.48 0) (size 0.59 0.64) (layers "B.Cu" "B.Paste" "B.Mask") (roundrect_rratio 0.25)
      (net 170 "I3C[1]_SCL_3V3") (pintype "passive"))
  )
)
